(kicad_pcb
	(version 20260206)
	(generator "pcbnew")
	(generator_version "10.0")
	(general
		(thickness 1.6)
		(legacy_teardrops no)
	)
	(paper "A4")
	(title_block
		(title "Wiwynn_Tioga_Pass_MB.brd")
		(comment 1 "Tioga Pass / footprint 1893 of 4770 (EU4D4), pads 1-42 of 49")
	)
	(layers
		(0 "F.Cu" signal "TOP")
		(4 "In1.Cu" signal "L2GND")
		(6 "In2.Cu" signal "L3")
		(8 "In3.Cu" signal "L4GND")
		(10 "In4.Cu" signal "L5")
		(12 "In5.Cu" signal "L6GND")
		(14 "In6.Cu" signal "L7VCC")
		(16 "In7.Cu" signal "L8VCC")
		(18 "In8.Cu" signal "L9GND")
		(20 "In9.Cu" signal "L10")
		(22 "In10.Cu" signal "L11GND")
		(24 "In11.Cu" signal "L12")
		(26 "In12.Cu" signal "L13GND")
		(2 "B.Cu" signal "BOTTOM")
		(9 "F.Adhes" user "F.Adhesive")
		(11 "B.Adhes" user "B.Adhesive")
		(13 "F.Paste" user "Package Geometry/Pastemask Top")
		(15 "B.Paste" user "Package Geometry/Pastemask Bottom")
		(5 "F.SilkS" user "Ref Des/Silkscreen Top")
		(7 "B.SilkS" user "Ref Des/Silkscreen Bottom")
		(1 "F.Mask" user "Board Geometry/Soldermask Top")
		(3 "B.Mask" user "Board Geometry/Soldermask Bottom")
		(17 "Dwgs.User" user "User.Drawings")
		(19 "Cmts.User" user "User.Comments")
		(21 "Eco1.User" user "User.Eco1")
		(23 "Eco2.User" user "User.Eco2")
		(25 "Edge.Cuts" user "Board Geometry/Outline")
		(27 "Margin" user)
		(31 "F.CrtYd" user "Package Geometry/Place Bound Top")
		(29 "B.CrtYd" user "Package Geometry/Place Bound Bottom")
		(35 "F.Fab" user "Ref Des/Assembly Top")
		(33 "B.Fab" user "Ref Des/Assembly Bottom")
	)
	(footprint ""
		(layer "F.Cu")
		(at 184.277 -69.85)
		(property "Reference" "EU4D4"
			(at -7.4422 -3.32613 0)
			(unlocked yes)
			(layer "F.SilkS")
			(effects
				(font
					(size 0.7874 0.5842)
					(thickness 0.1524)
				)
				(justify left)
			)
		)
		(property "Value" ""
			(at 0 0 0)
			(layer "F.Fab")
			(effects
				(font
					(size 1.27 1.27)
				)
			)
		)
		(duplicate_pad_numbers_are_jumpers no)
		(pad "1" smd custom
			(at -2.8956 -2.199894)
			(size 0.0508 0.0508)
			(layers "F.Cu" "F.Mask" "F.Paste")
			(net "VR_PVSA_CPU0_PWM")
			(options
				(clearance outline)
				(anchor circle)
			)
			(primitives
				(gr_poly
					(pts
						(arc
							(start 0.254 -0.1016)
							(mid 0.3556 0)
							(end 0.254 0.1016)
						)
						(xy -0.3556 0.1016) (xy -0.3556 -0.1016)
					)
					(width 0)
					(fill yes)
				)
			)
		)
		(pad "2" smd custom
			(at -2.8956 -1.800098)
			(size 0.0508 0.0508)
			(layers "F.Cu" "F.Mask" "F.Paste")
			(net "Net_274")
			(options
				(clearance outline)
				(anchor circle)
			)
			(primitives
				(gr_poly
					(pts
						(arc
							(start 0.254 -0.1016)
							(mid 0.3556 0)
							(end 0.254 0.1016)
						)
						(xy -0.3556 0.1016) (xy -0.3556 -0.1016)
					)
					(width 0)
					(fill yes)
				)
			)
		)
		(pad "3" smd custom
			(at -2.8956 -1.400048)
			(size 0.0508 0.0508)
			(layers "F.Cu" "F.Mask" "F.Paste")
			(net "VR_PVCCIN_CPU0_PWM5")
			(options
				(clearance outline)
				(anchor circle)
			)
			(primitives
				(gr_poly
					(pts
						(arc
							(start 0.254 -0.1016)
							(mid 0.3556 0)
							(end 0.254 0.1016)
						)
						(xy -0.3556 0.1016) (xy -0.3556 -0.1016)
					)
					(width 0)
					(fill yes)
				)
			)
		)
		(pad "4" smd custom
			(at -2.8956 -0.999998)
			(size 0.0508 0.0508)
			(layers "F.Cu" "F.Mask" "F.Paste")
			(net "VR_PVCCIN_CPU0_PWM4")
			(options
				(clearance outline)
				(anchor circle)
			)
			(primitives
				(gr_poly
					(pts
						(arc
							(start 0.254 -0.1016)
							(mid 0.3556 0)
							(end 0.254 0.1016)
						)
						(xy -0.3556 0.1016) (xy -0.3556 -0.1016)
					)
					(width 0)
					(fill yes)
				)
			)
		)
		(pad "5" smd custom
			(at -2.8956 -0.599948)
			(size 0.0508 0.0508)
			(layers "F.Cu" "F.Mask" "F.Paste")
			(net "VR_PVCCIN_CPU0_PWM3")
			(options
				(clearance outline)
				(anchor circle)
			)
			(primitives
				(gr_poly
					(pts
						(arc
							(start 0.254 -0.1016)
							(mid 0.3556 0)
							(end 0.254 0.1016)
						)
						(xy -0.3556 0.1016) (xy -0.3556 -0.1016)
					)
					(width 0)
					(fill yes)
				)
			)
		)
		(pad "6" smd custom
			(at -2.8956 -0.199898)
			(size 0.0508 0.0508)
			(layers "F.Cu" "F.Mask" "F.Paste")
			(net "VR_PVCCIN_CPU0_PWM2")
			(options
				(clearance outline)
				(anchor circle)
			)
			(primitives
				(gr_poly
					(pts
						(arc
							(start 0.254 -0.1016)
							(mid 0.3556 0)
							(end 0.254 0.1016)
						)
						(xy -0.3556 0.1016) (xy -0.3556 -0.1016)
					)
					(width 0)
					(fill yes)
				)
			)
		)
		(pad "7" smd custom
			(at -2.8956 0.199898)
			(size 0.0508 0.0508)
			(layers "F.Cu" "F.Mask" "F.Paste")
			(net "VR_PVCCIN_CPU0_PWM1")
			(options
				(clearance outline)
				(anchor circle)
			)
			(primitives
				(gr_poly
					(pts
						(arc
							(start 0.254 -0.1016)
							(mid 0.3556 0)
							(end 0.254 0.1016)
						)
						(xy -0.3556 0.1016) (xy -0.3556 -0.1016)
					)
					(width 0)
					(fill yes)
				)
			)
		)
		(pad "8" smd custom
			(at -2.8956 0.599948)
			(size 0.0508 0.0508)
			(layers "F.Cu" "F.Mask" "F.Paste")
			(net "SMB_VR_STBY_LVC3_SDA")
			(options
				(clearance outline)
				(anchor circle)
			)
			(primitives
				(gr_poly
					(pts
						(arc
							(start 0.254 -0.1016)
							(mid 0.3556 0)
							(end 0.254 0.1016)
						)
						(xy -0.3556 0.1016) (xy -0.3556 -0.1016)
					)
					(width 0)
					(fill yes)
				)
			)
		)
		(pad "9" smd custom
			(at -2.8956 0.999998)
			(size 0.0508 0.0508)
			(layers "F.Cu" "F.Mask" "F.Paste")
			(net "SMB_VR_STBY_LVC3_SCL")
			(options
				(clearance outline)
				(anchor circle)
			)
			(primitives
				(gr_poly
					(pts
						(arc
							(start 0.254 -0.1016)
							(mid 0.3556 0)
							(end 0.254 0.1016)
						)
						(xy -0.3556 0.1016) (xy -0.3556 -0.1016)
					)
					(width 0)
					(fill yes)
				)
			)
		)
		(pad "10" smd custom
			(at -2.8956 1.400048)
			(size 0.0508 0.0508)
			(layers "F.Cu" "F.Mask" "F.Paste")
			(net "Net_275")
			(options
				(clearance outline)
				(anchor circle)
			)
			(primitives
				(gr_poly
					(pts
						(arc
							(start 0.254 -0.1016)
							(mid 0.3556 0)
							(end 0.254 0.1016)
						)
						(xy -0.3556 0.1016) (xy -0.3556 -0.1016)
					)
					(width 0)
					(fill yes)
				)
			)
		)
		(pad "11" smd custom
			(at -2.8956 1.800098)
			(size 0.0508 0.0508)
			(layers "F.Cu" "F.Mask" "F.Paste")
			(net "VR_VRRDY_PVCCIN_CPU0")
			(options
				(clearance outline)
				(anchor circle)
			)
			(primitives
				(gr_poly
					(pts
						(arc
							(start 0.254 -0.1016)
							(mid 0.3556 0)
							(end 0.254 0.1016)
						)
						(xy -0.3556 0.1016) (xy -0.3556 -0.1016)
					)
					(width 0)
					(fill yes)
				)
			)
		)
		(pad "12" smd custom
			(at -2.8956 2.199894)
			(size 0.0508 0.0508)
			(layers "F.Cu" "F.Mask" "F.Paste")
			(net "VR_PVCCIN_CPU0_VREN")
			(options
				(clearance outline)
				(anchor circle)
			)
			(primitives
				(gr_poly
					(pts
						(arc
							(start 0.254 -0.1016)
							(mid 0.3556 0)
							(end 0.254 0.1016)
						)
						(xy -0.3556 0.1016) (xy -0.3556 -0.1016)
					)
					(width 0)
					(fill yes)
				)
			)
		)
		(pad "13" smd custom
			(at -2.199894 2.8956)
			(size 0.0508 0.0508)
			(layers "F.Cu" "F.Mask" "F.Paste")
			(net "IRQ_PVCCIN_CPU0_VRHOT_LVC3_R_N")
			(options
				(clearance outline)
				(anchor circle)
			)
			(primitives
				(gr_poly
					(pts
						(arc
							(start -0.1016 -0.254)
							(mid 0 -0.3556)
							(end 0.1016 -0.254)
						)
						(xy 0.1016 0.3556) (xy -0.1016 0.3556)
					)
					(width 0)
					(fill yes)
				)
			)
		)
		(pad "14" smd custom
			(at -1.800098 2.8956)
			(size 0.0508 0.0508)
			(layers "F.Cu" "F.Mask" "F.Paste")
			(net "FM_PVCCIN_CPU0_PWR_IN_ALERT_N")
			(options
				(clearance outline)
				(anchor circle)
			)
			(primitives
				(gr_poly
					(pts
						(arc
							(start -0.1016 -0.254)
							(mid 0 -0.3556)
							(end 0.1016 -0.254)
						)
						(xy 0.1016 0.3556) (xy -0.1016 0.3556)
					)
					(width 0)
					(fill yes)
				)
			)
		)
		(pad "15" smd custom
			(at -1.400048 2.8956)
			(size 0.0508 0.0508)
			(layers "F.Cu" "F.Mask" "F.Paste")
			(net "PWRGD_PVSA_CPU0_R")
			(options
				(clearance outline)
				(anchor circle)
			)
			(primitives
				(gr_poly
					(pts
						(arc
							(start -0.1016 -0.254)
							(mid 0 -0.3556)
							(end 0.1016 -0.254)
						)
						(xy 0.1016 0.3556) (xy -0.1016 0.3556)
					)
					(width 0)
					(fill yes)
				)
			)
		)
		(pad "16" smd custom
			(at -0.999998 2.8956)
			(size 0.0508 0.0508)
			(layers "F.Cu" "F.Mask" "F.Paste")
			(net "Net_219")
			(options
				(clearance outline)
				(anchor circle)
			)
			(primitives
				(gr_poly
					(pts
						(arc
							(start -0.1016 -0.254)
							(mid 0 -0.3556)
							(end 0.1016 -0.254)
						)
						(xy 0.1016 0.3556) (xy -0.1016 0.3556)
					)
					(width 0)
					(fill yes)
				)
			)
		)
		(pad "17" smd custom
			(at -0.599948 2.8956)
			(size 0.0508 0.0508)
			(layers "F.Cu" "F.Mask" "F.Paste")
			(net "SVID_VCLK_PVCCIN_CPU0")
			(options
				(clearance outline)
				(anchor circle)
			)
			(primitives
				(gr_poly
					(pts
						(arc
							(start -0.1016 -0.254)
							(mid 0 -0.3556)
							(end 0.1016 -0.254)
						)
						(xy 0.1016 0.3556) (xy -0.1016 0.3556)
					)
					(width 0)
					(fill yes)
				)
			)
		)
		(pad "18" smd custom
			(at -0.199898 2.8956)
			(size 0.0508 0.0508)
			(layers "F.Cu" "F.Mask" "F.Paste")
			(net "SVID_VDIO_PVCCIN_CPU0")
			(options
				(clearance outline)
				(anchor circle)
			)
			(primitives
				(gr_poly
					(pts
						(arc
							(start -0.1016 -0.254)
							(mid 0 -0.3556)
							(end 0.1016 -0.254)
						)
						(xy 0.1016 0.3556) (xy -0.1016 0.3556)
					)
					(width 0)
					(fill yes)
				)
			)
		)
		(pad "19" smd custom
			(at 0.199898 2.8956)
			(size 0.0508 0.0508)
			(layers "F.Cu" "F.Mask" "F.Paste")
			(net "SVID_VALERT_VCCIN_CPU0")
			(options
				(clearance outline)
				(anchor circle)
			)
			(primitives
				(gr_poly
					(pts
						(arc
							(start -0.1016 -0.254)
							(mid 0 -0.3556)
							(end 0.1016 -0.254)
						)
						(xy 0.1016 0.3556) (xy -0.1016 0.3556)
					)
					(width 0)
					(fill yes)
				)
			)
		)
		(pad "20" smd custom
			(at 0.599948 2.8956)
			(size 0.0508 0.0508)
			(layers "F.Cu" "F.Mask" "F.Paste")
			(net "PU_VR_PVCCIN_CPU0_FLT1_SMBALT_N")
			(options
				(clearance outline)
				(anchor circle)
			)
			(primitives
				(gr_poly
					(pts
						(arc
							(start -0.1016 -0.254)
							(mid 0 -0.3556)
							(end 0.1016 -0.254)
						)
						(xy 0.1016 0.3556) (xy -0.1016 0.3556)
					)
					(width 0)
					(fill yes)
				)
			)
		)
		(pad "21" smd custom
			(at 0.999998 2.8956)
			(size 0.0508 0.0508)
			(layers "F.Cu" "F.Mask" "F.Paste")
			(net "VSENSE_PVCCIN_CPU0_AVSP")
			(options
				(clearance outline)
				(anchor circle)
			)
			(primitives
				(gr_poly
					(pts
						(arc
							(start -0.1016 -0.254)
							(mid 0 -0.3556)
							(end 0.1016 -0.254)
						)
						(xy 0.1016 0.3556) (xy -0.1016 0.3556)
					)
					(width 0)
					(fill yes)
				)
			)
		)
		(pad "22" smd custom
			(at 1.400048 2.8956)
			(size 0.0508 0.0508)
			(layers "F.Cu" "F.Mask" "F.Paste")
			(net "VSENSE_PVCCIN_CPU0_N")
			(options
				(clearance outline)
				(anchor circle)
			)
			(primitives
				(gr_poly
					(pts
						(arc
							(start -0.1016 -0.254)
							(mid 0 -0.3556)
							(end 0.1016 -0.254)
						)
						(xy 0.1016 0.3556) (xy -0.1016 0.3556)
					)
					(width 0)
					(fill yes)
				)
			)
		)
		(pad "23" smd custom
			(at 1.800098 2.8956)
			(size 0.0508 0.0508)
			(layers "F.Cu" "F.Mask" "F.Paste")
			(net "VR_PVCCIN_CPU0_AIREF1")
			(options
				(clearance outline)
				(anchor circle)
			)
			(primitives
				(gr_poly
					(pts
						(arc
							(start -0.1016 -0.254)
							(mid 0 -0.3556)
							(end 0.1016 -0.254)
						)
						(xy 0.1016 0.3556) (xy -0.1016 0.3556)
					)
					(width 0)
					(fill yes)
				)
			)
		)
		(pad "24" smd custom
			(at 2.199894 2.8956)
			(size 0.0508 0.0508)
			(layers "F.Cu" "F.Mask" "F.Paste")
			(net "ISENSE_PVCCIN_CPU0_PH1_IMON")
			(options
				(clearance outline)
				(anchor circle)
			)
			(primitives
				(gr_poly
					(pts
						(arc
							(start -0.1016 -0.254)
							(mid 0 -0.3556)
							(end 0.1016 -0.254)
						)
						(xy 0.1016 0.3556) (xy -0.1016 0.3556)
					)
					(width 0)
					(fill yes)
				)
			)
		)
		(pad "25" smd custom
			(at 2.8956 2.199894)
			(size 0.0508 0.0508)
			(layers "F.Cu" "F.Mask" "F.Paste")
			(net "VR_PVCCIN_CPU0_AIREF2")
			(options
				(clearance outline)
				(anchor circle)
			)
			(primitives
				(gr_poly
					(pts
						(arc
							(start -0.254 0.1016)
							(mid -0.3556 0)
							(end -0.254 -0.1016)
						)
						(xy 0.3556 -0.1016) (xy 0.3556 0.1016)
					)
					(width 0)
					(fill yes)
				)
			)
		)
		(pad "26" smd custom
			(at 2.8956 1.800098)
			(size 0.0508 0.0508)
			(layers "F.Cu" "F.Mask" "F.Paste")
			(net "ISENSE_PVCCIN_CPU0_PH2_IMON")
			(options
				(clearance outline)
				(anchor circle)
			)
			(primitives
				(gr_poly
					(pts
						(arc
							(start -0.254 0.1016)
							(mid -0.3556 0)
							(end -0.254 -0.1016)
						)
						(xy 0.3556 -0.1016) (xy 0.3556 0.1016)
					)
					(width 0)
					(fill yes)
				)
			)
		)
		(pad "27" smd custom
			(at 2.8956 1.400048)
			(size 0.0508 0.0508)
			(layers "F.Cu" "F.Mask" "F.Paste")
			(net "VR_PVCCIN_CPU0_AIREF3")
			(options
				(clearance outline)
				(anchor circle)
			)
			(primitives
				(gr_poly
					(pts
						(arc
							(start -0.254 0.1016)
							(mid -0.3556 0)
							(end -0.254 -0.1016)
						)
						(xy 0.3556 -0.1016) (xy 0.3556 0.1016)
					)
					(width 0)
					(fill yes)
				)
			)
		)
		(pad "28" smd custom
			(at 2.8956 0.999998)
			(size 0.0508 0.0508)
			(layers "F.Cu" "F.Mask" "F.Paste")
			(net "ISENSE_PVCCIN_CPU0_PH3_IMON")
			(options
				(clearance outline)
				(anchor circle)
			)
			(primitives
				(gr_poly
					(pts
						(arc
							(start -0.254 0.1016)
							(mid -0.3556 0)
							(end -0.254 -0.1016)
						)
						(xy 0.3556 -0.1016) (xy 0.3556 0.1016)
					)
					(width 0)
					(fill yes)
				)
			)
		)
		(pad "29" smd custom
			(at 2.8956 0.599948)
			(size 0.0508 0.0508)
			(layers "F.Cu" "F.Mask" "F.Paste")
			(net "VR_PVCCIN_CPU0_AIREF4")
			(options
				(clearance outline)
				(anchor circle)
			)
			(primitives
				(gr_poly
					(pts
						(arc
							(start -0.254 0.1016)
							(mid -0.3556 0)
							(end -0.254 -0.1016)
						)
						(xy 0.3556 -0.1016) (xy 0.3556 0.1016)
					)
					(width 0)
					(fill yes)
				)
			)
		)
		(pad "30" smd custom
			(at 2.8956 0.199898)
			(size 0.0508 0.0508)
			(layers "F.Cu" "F.Mask" "F.Paste")
			(net "ISENSE_PVCCIN_CPU0_PH4_IMON")
			(options
				(clearance outline)
				(anchor circle)
			)
			(primitives
				(gr_poly
					(pts
						(arc
							(start -0.254 0.1016)
							(mid -0.3556 0)
							(end -0.254 -0.1016)
						)
						(xy 0.3556 -0.1016) (xy 0.3556 0.1016)
					)
					(width 0)
					(fill yes)
				)
			)
		)
		(pad "31" smd custom
			(at 2.8956 -0.199898)
			(size 0.0508 0.0508)
			(layers "F.Cu" "F.Mask" "F.Paste")
			(net "VR_PVCCIN_CPU0_AIREF5")
			(options
				(clearance outline)
				(anchor circle)
			)
			(primitives
				(gr_poly
					(pts
						(arc
							(start -0.254 0.1016)
							(mid -0.3556 0)
							(end -0.254 -0.1016)
						)
						(xy 0.3556 -0.1016) (xy 0.3556 0.1016)
					)
					(width 0)
					(fill yes)
				)
			)
		)
		(pad "32" smd custom
			(at 2.8956 -0.599948)
			(size 0.0508 0.0508)
			(layers "F.Cu" "F.Mask" "F.Paste")
			(net "ISENSE_PVCCIN_CPU0_PH5_IMON")
			(options
				(clearance outline)
				(anchor circle)
			)
			(primitives
				(gr_poly
					(pts
						(arc
							(start -0.254 0.1016)
							(mid -0.3556 0)
							(end -0.254 -0.1016)
						)
						(xy 0.3556 -0.1016) (xy 0.3556 0.1016)
					)
					(width 0)
					(fill yes)
				)
			)
		)
		(pad "33" smd custom
			(at 2.8956 -0.999998)
			(size 0.0508 0.0508)
			(layers "F.Cu" "F.Mask" "F.Paste")
			(net "Net_273")
			(options
				(clearance outline)
				(anchor circle)
			)
			(primitives
				(gr_poly
					(pts
						(arc
							(start -0.254 0.1016)
							(mid -0.3556 0)
							(end -0.254 -0.1016)
						)
						(xy 0.3556 -0.1016) (xy 0.3556 0.1016)
					)
					(width 0)
					(fill yes)
				)
			)
		)
		(pad "34" smd custom
			(at 2.8956 -1.400048)
			(size 0.0508 0.0508)
			(layers "F.Cu" "F.Mask" "F.Paste")
			(net "Net_290")
			(options
				(clearance outline)
				(anchor circle)
			)
			(primitives
				(gr_poly
					(pts
						(arc
							(start -0.254 0.1016)
							(mid -0.3556 0)
							(end -0.254 -0.1016)
						)
						(xy 0.3556 -0.1016) (xy 0.3556 0.1016)
					)
					(width 0)
					(fill yes)
				)
			)
		)
		(pad "35" smd custom
			(at 2.8956 -1.800098)
			(size 0.0508 0.0508)
			(layers "F.Cu" "F.Mask" "F.Paste")
			(net "VSENSE_PVSA_CPU0_BVSP")
			(options
				(clearance outline)
				(anchor circle)
			)
			(primitives
				(gr_poly
					(pts
						(arc
							(start -0.254 0.1016)
							(mid -0.3556 0)
							(end -0.254 -0.1016)
						)
						(xy 0.3556 -0.1016) (xy 0.3556 0.1016)
					)
					(width 0)
					(fill yes)
				)
			)
		)
		(pad "36" smd custom
			(at 2.8956 -2.199894)
			(size 0.0508 0.0508)
			(layers "F.Cu" "F.Mask" "F.Paste")
			(net "VSENSE_PVSA_CPU0_N")
			(options
				(clearance outline)
				(anchor circle)
			)
			(primitives
				(gr_poly
					(pts
						(arc
							(start -0.254 0.1016)
							(mid -0.3556 0)
							(end -0.254 -0.1016)
						)
						(xy 0.3556 -0.1016) (xy 0.3556 0.1016)
					)
					(width 0)
					(fill yes)
				)
			)
		)
		(pad "37" smd custom
			(at 2.199894 -2.8956)
			(size 0.0508 0.0508)
			(layers "F.Cu" "F.Mask" "F.Paste")
			(net "VR_PVSA_CPU0_BIREF1")
			(options
				(clearance outline)
				(anchor circle)
			)
			(primitives
				(gr_poly
					(pts
						(arc
							(start 0.1016 0.254)
							(mid 0 0.3556)
							(end -0.1016 0.254)
						)
						(xy -0.1016 -0.3556) (xy 0.1016 -0.3556)
					)
					(width 0)
					(fill yes)
				)
			)
		)
		(pad "38" smd custom
			(at 1.800098 -2.8956)
			(size 0.0508 0.0508)
			(layers "F.Cu" "F.Mask" "F.Paste")
			(net "ISENSE_PVSA_CPU0_IMON")
			(options
				(clearance outline)
				(anchor circle)
			)
			(primitives
				(gr_poly
					(pts
						(arc
							(start 0.1016 0.254)
							(mid 0 0.3556)
							(end -0.1016 0.254)
						)
						(xy -0.1016 -0.3556) (xy 0.1016 -0.3556)
					)
					(width 0)
					(fill yes)
				)
			)
		)
		(pad "39" smd custom
			(at 1.400048 -2.8956)
			(size 0.0508 0.0508)
			(layers "F.Cu" "F.Mask" "F.Paste")
			(net "PU_VR_PVCCIN_CPU0_IMON")
			(options
				(clearance outline)
				(anchor circle)
			)
			(primitives
				(gr_poly
					(pts
						(arc
							(start 0.1016 0.254)
							(mid 0 0.3556)
							(end -0.1016 0.254)
						)
						(xy -0.1016 -0.3556) (xy 0.1016 -0.3556)
					)
					(width 0)
					(fill yes)
				)
			)
		)
		(pad "40" smd custom
			(at 0.999998 -2.8956)
			(size 0.0508 0.0508)
			(layers "F.Cu" "F.Mask" "F.Paste")
			(net "Net_292")
			(options
				(clearance outline)
				(anchor circle)
			)
			(primitives
				(gr_poly
					(pts
						(arc
							(start 0.1016 0.254)
							(mid 0 0.3556)
							(end -0.1016 0.254)
						)
						(xy -0.1016 -0.3556) (xy 0.1016 -0.3556)
					)
					(width 0)
					(fill yes)
				)
			)
		)
		(pad "41" smd custom
			(at 0.599948 -2.8956)
			(size 0.0508 0.0508)
			(layers "F.Cu" "F.Mask" "F.Paste")
			(net "VR_PVCCIN_CPU0_XADDR2")
			(options
				(clearance outline)
				(anchor circle)
			)
			(primitives
				(gr_poly
					(pts
						(arc
							(start 0.1016 0.254)
							(mid 0 0.3556)
							(end -0.1016 0.254)
						)
						(xy -0.1016 -0.3556) (xy 0.1016 -0.3556)
					)
					(width 0)
					(fill yes)
				)
			)
		)
		(pad "42" smd custom
			(at 0.199898 -2.8956)
			(size 0.0508 0.0508)
			(layers "F.Cu" "F.Mask" "F.Paste")
			(net "A_TSENSE_PVSA_CPU0")
			(options
				(clearance outline)
				(anchor circle)
			)
			(primitives
				(gr_poly
					(pts
						(arc
							(start 0.1016 0.254)
							(mid 0 0.3556)
							(end -0.1016 0.254)
						)
						(xy -0.1016 -0.3556) (xy 0.1016 -0.3556)
					)
					(width 0)
					(fill yes)
				)
			)
		)
	)
)
